# T6G (Grand Teton) — schematic netlist excerpt (pin names and nets, part order shuffled) for the footprints in the layout excerpt that follows; sources: Cadence DE-HDL packaged netlist, KiCad conversion of 04192023_DAF0TMB3IC0_F0TG_MB_C_brd_V02_OCP.brd

C2127  Q_CAP  22UF 4V 20% X6S  pkg C0402  page 74 : A = PVDDIO_P1 ; B = GND
D85  Q_LED  IC  pkg SMLF  page 256 : A = LED_PWRGD_PVDD18_S5_P1_R ; C = LED_PWRGD_PVDD18_S5_P1_D

(kicad_pcb
	(version 20260206)
	(generator "pcbnew")
	(generator_version "10.0")
	(general
		(thickness 1.6)
		(legacy_teardrops no)
	)
	(paper "A4")
	(title_block
		(title "04192023_DAF0TMB3IC0_F0TG_MB_C_brd_V02_OCP.brd")
		(comment 1 "Grand Teton / footprints 1990-1991 of 8354")
	)
	(layers
		(0 "F.Cu" signal "TOP")
		(4 "In1.Cu" signal "GND")
		(6 "In2.Cu" signal "IN1")
		(8 "In3.Cu" signal "GND1")
		(10 "In4.Cu" signal "IN2")
		(12 "In5.Cu" signal "GND2")
		(14 "In6.Cu" signal "IN3")
		(16 "In7.Cu" signal "GND3")
		(18 "In8.Cu" signal "VCC")
		(20 "In9.Cu" signal "VCC1")
		(22 "In10.Cu" signal "GND4")
		(24 "In11.Cu" signal "IN4")
		(26 "In12.Cu" signal "GND5")
		(28 "In13.Cu" signal "IN5")
		(30 "In14.Cu" signal "GND6")
		(32 "In15.Cu" signal "IN6")
		(34 "In16.Cu" signal "GND7")
		(2 "B.Cu" signal "BOTTOM")
		(9 "F.Adhes" user "F.Adhesive")
		(11 "B.Adhes" user "B.Adhesive")
		(13 "F.Paste" user "Package Geometry/Pastemask Top")
		(15 "B.Paste" user "Package Geometry/Pastemask Bottom")
		(5 "F.SilkS" user "Ref Des/Silkscreen Top")
		(7 "B.SilkS" user "Ref Des/Silkscreen Bottom")
		(1 "F.Mask" user "Board Geometry/Soldermask Top")
		(3 "B.Mask" user "Board Geometry/Soldermask Bottom")
		(17 "Dwgs.User" user "User.Drawings")
		(19 "Cmts.User" user "User.Comments")
		(21 "Eco1.User" user "User.Eco1")
		(23 "Eco2.User" user "User.Eco2")
		(25 "Edge.Cuts" user "Board Geometry/Outline")
		(27 "Margin" user)
		(31 "F.CrtYd" user "Package Geometry/Place Bound Top")
		(29 "B.CrtYd" user "Package Geometry/Place Bound Bottom")
		(35 "F.Fab" user "Ref Des/Assembly Top")
		(33 "B.Fab" user "Ref Des/Assembly Bottom")
	)
	(footprint ""
		(layer "F.Cu")
		(at 346.987876 -70.098412 90)
		(property "Reference" "D85"
			(at -3.934714 -0.691642 90)
			(unlocked yes)
			(layer "F.SilkS")
			(effects
				(font
					(size 0.7874 0.5842)
					(thickness 0.1524)
				)
				(justify left)
			)
		)
		(property "Value" ""
			(at 0 0 90)
			(layer "F.Fab")
			(effects
				(font
					(size 1.27 1.27)
				)
			)
		)
		(duplicate_pad_numbers_are_jumpers no)
		(fp_line
			(start 1.16078 -0.4826)
			(end 1.16078 0.4826)
			(stroke
				(width 0.1524)
				(type default)
			)
			(layer "F.SilkS")
		)
		(fp_line
			(start 1.03378 -0.4826)
			(end 1.03378 0.4826)
			(stroke
				(width 0.1524)
				(type default)
			)
			(layer "F.SilkS")
		)
		(fp_line
			(start 0.90678 -0.4826)
			(end 0.90678 0.4826)
			(stroke
				(width 0.1524)
				(type default)
			)
			(layer "F.SilkS")
		)
		(fp_line
			(start -0.64008 -0.4826)
			(end 1.16078 -0.4826)
			(stroke
				(width 0.1524)
				(type default)
			)
			(layer "F.SilkS")
		)
		(fp_line
			(start -0.79248 -0.4826)
			(end 1.03378 -0.4826)
			(stroke
				(width 0.1524)
				(type default)
			)
			(layer "F.SilkS")
		)
		(fp_line
			(start -0.89408 -0.4826)
			(end 0.90678 -0.4826)
			(stroke
				(width 0.1524)
				(type default)
			)
			(layer "F.SilkS")
		)
		(fp_line
			(start 1.16078 0.4826)
			(end -0.64008 0.4826)
			(stroke
				(width 0.1524)
				(type default)
			)
			(layer "F.SilkS")
		)
		(fp_line
			(start 1.03378 0.4826)
			(end -0.79248 0.4826)
			(stroke
				(width 0.1524)
				(type default)
			)
			(layer "F.SilkS")
		)
		(fp_line
			(start 0.90678 0.4826)
			(end -0.90678 0.4826)
			(stroke
				(width 0.1524)
				(type default)
			)
			(layer "F.SilkS")
		)
		(fp_line
			(start -0.90678 0.4826)
			(end -0.90678 -0.4699)
			(stroke
				(width 0.1524)
				(type default)
			)
			(layer "F.SilkS")
		)
		(fp_line
			(start 0.499872 -0.249936)
			(end 0.499872 0.249936)
			(stroke
				(width 0.1)
				(type default)
			)
			(layer "F.Fab")
		)
		(fp_line
			(start -0.499872 -0.249936)
			(end 0.499872 -0.249936)
			(stroke
				(width 0.1)
				(type default)
			)
			(layer "F.Fab")
		)
		(fp_line
			(start 0.499872 0.249936)
			(end -0.499872 0.249936)
			(stroke
				(width 0.1)
				(type default)
			)
			(layer "F.Fab")
		)
		(fp_line
			(start -0.499872 0.249936)
			(end -0.499872 -0.249936)
			(stroke
				(width 0.1)
				(type default)
			)
			(layer "F.Fab")
		)
		(pad "A" smd rect
			(at -0.47498 0 90)
			(size 0.6096 0.7112)
			(layers "F.Cu" "F.Mask" "F.Paste")
			(net "LED_PWRGD_PVDD18_S5_P1_R")
		)
		(pad "C" smd rect
			(at 0.47498 0 90)
			(size 0.6096 0.7112)
			(layers "F.Cu" "F.Mask" "F.Paste")
			(net "LED_PWRGD_PVDD18_S5_P1_D")
		)
	)
	(footprint ""
		(layer "F.Cu")
		(at 108.355892 -259.845302)
		(property "Reference" "C2127"
			(at 0 0 0)
			(layer "F.SilkS")
			(hide yes)
			(effects
				(font
					(size 1.27 1.27)
				)
			)
		)
		(property "Value" ""
			(at 0 0 0)
			(layer "F.Fab")
			(effects
				(font
					(size 1.27 1.27)
				)
			)
		)
		(duplicate_pad_numbers_are_jumpers no)
		(fp_line
			(start -0.7874 -0.4064)
			(end 0.7874 -0.4064)
			(stroke
				(width 0.1524)
				(type default)
			)
			(layer "F.SilkS")
		)
		(fp_line
			(start -0.7874 0.4064)
			(end -0.7874 -0.4064)
			(stroke
				(width 0.1524)
				(type default)
			)
			(layer "F.SilkS")
		)
		(fp_line
			(start 0.7874 -0.4064)
			(end 0.7874 0.4064)
			(stroke
				(width 0.1524)
				(type default)
			)
			(layer "F.SilkS")
		)
		(fp_line
			(start 0.7874 0.4064)
			(end -0.7874 0.4064)
			(stroke
				(width 0.1524)
				(type default)
			)
			(layer "F.SilkS")
		)
		(fp_line
			(start -0.67945 -0.305054)
			(end -0.12065 -0.305054)
			(stroke
				(width 0.1)
				(type default)
			)
			(layer "F.Fab")
		)
		(fp_line
			(start -0.67945 0.3048)
			(end -0.67945 -0.305054)
			(stroke
				(width 0.1)
				(type default)
			)
			(layer "F.Fab")
		)
		(fp_line
			(start -0.12065 -0.305054)
			(end -0.12065 -0.2794)
			(stroke
				(width 0.1)
				(type default)
			)
			(layer "F.Fab")
		)
		(fp_line
			(start -0.12065 -0.2794)
			(end 0.12065 -0.2794)
			(stroke
				(width 0.1)
				(type default)
			)
			(layer "F.Fab")
		)
		(fp_line
			(start -0.12065 0.2794)
			(end -0.12065 0.3048)
			(stroke
				(width 0.1)
				(type default)
			)
			(layer "F.Fab")
		)
		(fp_line
			(start -0.12065 0.3048)
			(end -0.67945 0.3048)
			(stroke
				(width 0.1)
				(type default)
			)
			(layer "F.Fab")
		)
		(fp_line
			(start 0.120396 0.2794)
			(end -0.12065 0.2794)
			(stroke
				(width 0.1)
				(type default)
			)
			(layer "F.Fab")
		)
		(fp_line
			(start 0.120396 0.3048)
			(end 0.120396 0.2794)
			(stroke
				(width 0.1)
				(type default)
			)
			(layer "F.Fab")
		)
		(fp_line
			(start 0.12065 -0.3048)
			(end 0.67945 -0.3048)
			(stroke
				(width 0.1)
				(type default)
			)
			(layer "F.Fab")
		)
		(fp_line
			(start 0.12065 -0.2794)
			(end 0.12065 -0.3048)
			(stroke
				(width 0.1)
				(type default)
			)
			(layer "F.Fab")
		)
		(fp_line
			(start 0.67945 -0.3048)
			(end 0.67945 0.3048)
			(stroke
				(width 0.1)
				(type default)
			)
			(layer "F.Fab")
		)
		(fp_line
			(start 0.67945 0.3048)
			(end 0.120396 0.3048)
			(stroke
				(width 0.1)
				(type default)
			)
			(layer "F.Fab")
		)
		(pad "1" smd circle
			(at -0.40005 0)
			(size 0 0)
			(layers "F.Cu" "F.Mask" "F.Paste")
			(net "PVDDIO_P1")
		)
		(pad "2" smd circle
			(at 0.40005 0)
			(size 0 0)
			(layers "F.Cu" "F.Mask" "F.Paste")
			(net "GND")
		)
	)
)
